(kicad_pcb
	(version 20260206)
	(generator "pcbnew")
	(generator_version "10.0")
	(general
		(thickness 1.6)
		(legacy_teardrops no)
	)
	(paper "A4")
	(title_block
		(title "Wiwynn_Tioga_Pass_MB.brd")
		(comment 1 "Tioga Pass / footprints 3996-4002 of 4770")
	)
	(layers
		(0 "F.Cu" signal "TOP")
		(4 "In1.Cu" signal "L2GND")
		(6 "In2.Cu" signal "L3")
		(8 "In3.Cu" signal "L4GND")
		(10 "In4.Cu" signal "L5")
		(12 "In5.Cu" signal "L6GND")
		(14 "In6.Cu" signal "L7VCC")
		(16 "In7.Cu" signal "L8VCC")
		(18 "In8.Cu" signal "L9GND")
		(20 "In9.Cu" signal "L10")
		(22 "In10.Cu" signal "L11GND")
		(24 "In11.Cu" signal "L12")
		(26 "In12.Cu" signal "L13GND")
		(2 "B.Cu" signal "BOTTOM")
		(9 "F.Adhes" user "F.Adhesive")
		(11 "B.Adhes" user "B.Adhesive")
		(13 "F.Paste" user "Package Geometry/Pastemask Top")
		(15 "B.Paste" user "Package Geometry/Pastemask Bottom")
		(5 "F.SilkS" user "Ref Des/Silkscreen Top")
		(7 "B.SilkS" user "Ref Des/Silkscreen Bottom")
		(1 "F.Mask" user "Board Geometry/Soldermask Top")
		(3 "B.Mask" user "Board Geometry/Soldermask Bottom")
		(17 "Dwgs.User" user "User.Drawings")
		(19 "Cmts.User" user "User.Comments")
		(21 "Eco1.User" user "User.Eco1")
		(23 "Eco2.User" user "User.Eco2")
		(25 "Edge.Cuts" user "Board Geometry/Outline")
		(27 "Margin" user)
		(31 "F.CrtYd" user "Package Geometry/Place Bound Top")
		(29 "B.CrtYd" user "Package Geometry/Place Bound Bottom")
		(35 "F.Fab" user "Ref Des/Assembly Top")
		(33 "B.Fab" user "Ref Des/Assembly Bottom")
	)
	(footprint ""
		(layer "B.Cu")
		(at 449.9864 -8.0518 -90)
		(property "Reference" "R2U43"
			(at 0 0 90)
			(layer "B.SilkS")
			(hide yes)
			(effects
				(font
					(size 1.27 1.27)
				)
				(justify mirror)
			)
		)
		(property "Value" ""
			(at 0 0 90)
			(layer "B.Fab")
			(effects
				(font
					(size 1.27 1.27)
				)
				(justify mirror)
			)
		)
		(duplicate_pad_numbers_are_jumpers no)
		(fp_poly
			(pts
				(xy 0.2794 -0.1016) (xy -0.2794 -0.1016) (xy -0.2794 0.9906) (xy 0.2794 0.9906)
			)
			(stroke
				(width 0)
				(type default)
			)
			(fill no)
			(layer "B.CrtYd")
		)
		(fp_line
			(start -0.2794 0.9906)
			(end -0.2794 -0.1016)
			(stroke
				(width 0.1)
				(type default)
			)
			(layer "B.Fab")
		)
		(fp_line
			(start 0.2794 0.9906)
			(end -0.2794 0.9906)
			(stroke
				(width 0.1)
				(type default)
			)
			(layer "B.Fab")
		)
		(fp_line
			(start -0.2794 -0.1016)
			(end 0.2794 -0.1016)
			(stroke
				(width 0.1)
				(type default)
			)
			(layer "B.Fab")
		)
		(fp_line
			(start 0.2794 -0.1016)
			(end 0.2794 0.9906)
			(stroke
				(width 0.1)
				(type default)
			)
			(layer "B.Fab")
		)
		(pad "1" smd rect
			(at 0 0 90)
			(size 0.508 0.508)
			(layers "B.Cu" "B.Mask" "B.Paste")
			(net "P3V_BAT_SOURCE")
		)
		(pad "2" smd rect
			(at 0 0.889 90)
			(size 0.508 0.508)
			(layers "B.Cu" "B.Mask" "B.Paste")
			(net "A_P3V_BAT_R")
		)
		(zone
			(layer "B.Cu")
			(hatch none 0.5)
			(connect_pads
				(clearance 0)
			)
			(min_thickness 0.25)
			(keepout
				(tracks not_allowed)
				(vias allowed)
				(pads allowed)
				(copperpour not_allowed)
				(footprints allowed)
			)
			(placement
				(enabled no)
				(sheetname "")
			)
			(fill
				(thermal_gap 0.5)
				(thermal_bridge_width 0.5)
				(island_removal_mode 0)
			)
			(polygon
				(pts
					(xy 449.3514 -7.7978) (xy 449.3514 -8.3058) (xy 449.7324 -8.3058) (xy 449.7324 -7.7978)
				)
			)
		)
		(zone
			(layer "B.Cu")
			(hatch none 0.5)
			(connect_pads
				(clearance 0)
			)
			(min_thickness 0.25)
			(keepout
				(tracks allowed)
				(vias not_allowed)
				(pads allowed)
				(copperpour not_allowed)
				(footprints allowed)
			)
			(placement
				(enabled no)
				(sheetname "")
			)
			(fill
				(thermal_gap 0.5)
				(thermal_bridge_width 0.5)
				(island_removal_mode 0)
			)
			(polygon
				(pts
					(xy 449.7324 -7.7978) (xy 449.7324 -8.3058) (xy 449.3514 -8.3058) (xy 449.3514 -7.7978)
				)
			)
		)
	)
	(footprint ""
		(layer "B.Cu")
		(at 472.127326 -15.951962)
		(property "Reference" "C2U2"
			(at 0 0 0)
			(layer "B.SilkS")
			(hide yes)
			(effects
				(font
					(size 1.27 1.27)
				)
				(justify mirror)
			)
		)
		(property "Value" ""
			(at 0 0 0)
			(layer "B.Fab")
			(effects
				(font
					(size 1.27 1.27)
				)
				(justify mirror)
			)
		)
		(duplicate_pad_numbers_are_jumpers no)
		(fp_rect
			(start 0.7239 -0.2159)
			(end -0.7239 1.9939)
			(stroke
				(width 0)
				(type default)
			)
			(fill no)
			(layer "B.CrtYd")
		)
		(fp_line
			(start -0.7239 -0.2159)
			(end 0.7239 -0.2159)
			(stroke
				(width 0.1)
				(type default)
			)
			(layer "B.Fab")
		)
		(fp_line
			(start -0.7239 1.9939)
			(end -0.7239 -0.2159)
			(stroke
				(width 0.1)
				(type default)
			)
			(layer "B.Fab")
		)
		(fp_line
			(start 0.7239 -0.2159)
			(end 0.7239 1.9939)
			(stroke
				(width 0.1)
				(type default)
			)
			(layer "B.Fab")
		)
		(fp_line
			(start 0.7239 1.9939)
			(end -0.7239 1.9939)
			(stroke
				(width 0.1)
				(type default)
			)
			(layer "B.Fab")
		)
		(pad "1" smd rect
			(at 0 0 180)
			(size 1.27 1.016)
			(layers "B.Cu" "B.Mask" "B.Paste")
			(net "P3V3")
		)
		(pad "2" smd rect
			(at 0 1.778 180)
			(size 1.27 1.016)
			(layers "B.Cu" "B.Mask" "B.Paste")
			(net "GND")
		)
		(zone
			(layer "B.Cu")
			(hatch none 0.5)
			(connect_pads
				(clearance 0)
			)
			(min_thickness 0.25)
			(keepout
				(tracks not_allowed)
				(vias allowed)
				(pads allowed)
				(copperpour not_allowed)
				(footprints allowed)
			)
			(placement
				(enabled no)
				(sheetname "")
			)
			(fill
				(thermal_gap 0.5)
				(thermal_bridge_width 0.5)
				(island_removal_mode 0)
			)
			(polygon
				(pts
					(xy 472.762326 -15.443962) (xy 471.492326 -15.443962) (xy 471.492326 -14.681962) (xy 472.762326 -14.681962)
				)
			)
		)
	)
	(footprint ""
		(layer "B.Cu")
		(at 80.153002 -86.743286 -90)
		(property "Reference" "R8P2"
			(at 0 0 90)
			(layer "B.SilkS")
			(hide yes)
			(effects
				(font
					(size 1.27 1.27)
				)
				(justify mirror)
			)
		)
		(property "Value" ""
			(at 0 0 90)
			(layer "B.Fab")
			(effects
				(font
					(size 1.27 1.27)
				)
				(justify mirror)
			)
		)
		(duplicate_pad_numbers_are_jumpers no)
		(fp_poly
			(pts
				(xy 0.2794 -0.1016) (xy -0.2794 -0.1016) (xy -0.2794 0.9906) (xy 0.2794 0.9906)
			)
			(stroke
				(width 0)
				(type default)
			)
			(fill no)
			(layer "B.CrtYd")
		)
		(fp_line
			(start -0.2794 0.9906)
			(end -0.2794 -0.1016)
			(stroke
				(width 0.1)
				(type default)
			)
			(layer "B.Fab")
		)
		(fp_line
			(start 0.2794 0.9906)
			(end -0.2794 0.9906)
			(stroke
				(width 0.1)
				(type default)
			)
			(layer "B.Fab")
		)
		(fp_line
			(start -0.2794 -0.1016)
			(end 0.2794 -0.1016)
			(stroke
				(width 0.1)
				(type default)
			)
			(layer "B.Fab")
		)
		(fp_line
			(start 0.2794 -0.1016)
			(end 0.2794 0.9906)
			(stroke
				(width 0.1)
				(type default)
			)
			(layer "B.Fab")
		)
		(pad "1" smd rect
			(at 0 0 90)
			(size 0.508 0.508)
			(layers "B.Cu" "B.Mask" "B.Paste")
			(net "PD_CPU1_TEST13")
		)
		(pad "2" smd rect
			(at 0 0.889 90)
			(size 0.508 0.508)
			(layers "B.Cu" "B.Mask" "B.Paste")
			(net "GND")
		)
		(zone
			(layer "B.Cu")
			(hatch none 0.5)
			(connect_pads
				(clearance 0)
			)
			(min_thickness 0.25)
			(keepout
				(tracks not_allowed)
				(vias allowed)
				(pads allowed)
				(copperpour not_allowed)
				(footprints allowed)
			)
			(placement
				(enabled no)
				(sheetname "")
			)
			(fill
				(thermal_gap 0.5)
				(thermal_bridge_width 0.5)
				(island_removal_mode 0)
			)
			(polygon
				(pts
					(xy 79.518002 -86.489286) (xy 79.518002 -86.997286) (xy 79.899002 -86.997286) (xy 79.899002 -86.489286)
				)
			)
		)
		(zone
			(layer "B.Cu")
			(hatch none 0.5)
			(connect_pads
				(clearance 0)
			)
			(min_thickness 0.25)
			(keepout
				(tracks allowed)
				(vias not_allowed)
				(pads allowed)
				(copperpour not_allowed)
				(footprints allowed)
			)
			(placement
				(enabled no)
				(sheetname "")
			)
			(fill
				(thermal_gap 0.5)
				(thermal_bridge_width 0.5)
				(island_removal_mode 0)
			)
			(polygon
				(pts
					(xy 79.899002 -86.489286) (xy 79.899002 -86.997286) (xy 79.518002 -86.997286) (xy 79.518002 -86.489286)
				)
			)
		)
	)
	(footprint ""
		(layer "B.Cu")
		(at 393.286234 -152.73274 90)
		(property "Reference" "C2L8"
			(at 0 0 90)
			(layer "B.SilkS")
			(hide yes)
			(effects
				(font
					(size 1.27 1.27)
				)
				(justify mirror)
			)
		)
		(property "Value" ""
			(at 0 0 90)
			(layer "B.Fab")
			(effects
				(font
					(size 1.27 1.27)
				)
				(justify mirror)
			)
		)
		(duplicate_pad_numbers_are_jumpers no)
		(fp_poly
			(pts
				(xy -0.3048 -0.1016) (xy -0.3048 0.9906) (xy 0.3048 0.9906) (xy 0.3048 -0.1016)
			)
			(stroke
				(width 0)
				(type default)
			)
			(fill no)
			(layer "B.CrtYd")
		)
		(fp_line
			(start 0.3048 -0.1016)
			(end 0.3048 0.9906)
			(stroke
				(width 0.1)
				(type default)
			)
			(layer "B.Fab")
		)
		(fp_line
			(start -0.3048 -0.1016)
			(end 0.3048 -0.1016)
			(stroke
				(width 0.1)
				(type default)
			)
			(layer "B.Fab")
		)
		(fp_line
			(start 0.3048 0.9906)
			(end -0.3048 0.9906)
			(stroke
				(width 0.1)
				(type default)
			)
			(layer "B.Fab")
		)
		(fp_line
			(start -0.3048 0.9906)
			(end -0.3048 -0.1016)
			(stroke
				(width 0.1)
				(type default)
			)
			(layer "B.Fab")
		)
		(pad "1" smd rect
			(at 0 0 270)
			(size 0.508 0.508)
			(layers "B.Cu" "B.Mask" "B.Paste")
			(net "VR_PVNN_PCH_VDD")
		)
		(pad "2" smd rect
			(at 0 0.889 270)
			(size 0.508 0.508)
			(layers "B.Cu" "B.Mask" "B.Paste")
			(net "GND")
		)
		(zone
			(layer "B.Cu")
			(hatch none 0.5)
			(connect_pads
				(clearance 0)
			)
			(min_thickness 0.25)
			(keepout
				(tracks allowed)
				(vias not_allowed)
				(pads allowed)
				(copperpour not_allowed)
				(footprints allowed)
			)
			(placement
				(enabled no)
				(sheetname "")
			)
			(fill
				(thermal_gap 0.5)
				(thermal_bridge_width 0.5)
				(island_removal_mode 0)
			)
			(polygon
				(pts
					(xy 393.540234 -152.98674) (xy 393.540234 -152.47874) (xy 393.921234 -152.47874) (xy 393.921234 -152.98674)
				)
			)
		)
		(zone
			(layer "B.Cu")
			(hatch none 0.5)
			(connect_pads
				(clearance 0)
			)
			(min_thickness 0.25)
			(keepout
				(tracks not_allowed)
				(vias allowed)
				(pads allowed)
				(copperpour not_allowed)
				(footprints allowed)
			)
			(placement
				(enabled no)
				(sheetname "")
			)
			(fill
				(thermal_gap 0.5)
				(thermal_bridge_width 0.5)
				(island_removal_mode 0)
			)
			(polygon
				(pts
					(xy 393.921234 -152.98674) (xy 393.921234 -152.47874) (xy 393.540234 -152.47874) (xy 393.540234 -152.98674)
				)
			)
		)
	)
	(footprint ""
		(layer "B.Cu")
		(at 401.599146 -36.331652 90)
		(property "Reference" "R25W105"
			(at 0.8382 -0.67818 90)
			(unlocked yes)
			(layer "B.SilkS")
			(effects
				(font
					(size 0.4064 0.254)
					(thickness 0.1524)
				)
				(justify left mirror)
			)
		)
		(property "Value" ""
			(at 0 0 90)
			(layer "B.Fab")
			(effects
				(font
					(size 1.27 1.27)
				)
				(justify mirror)
			)
		)
		(duplicate_pad_numbers_are_jumpers no)
		(fp_poly
			(pts
				(xy 0.2794 -0.1016) (xy -0.2794 -0.1016) (xy -0.2794 0.9906) (xy 0.2794 0.9906)
			)
			(stroke
				(width 0)
				(type default)
			)
			(fill no)
			(layer "B.CrtYd")
		)
		(fp_line
			(start 0.2794 -0.1016)
			(end 0.2794 0.9906)
			(stroke
				(width 0.1)
				(type default)
			)
			(layer "B.Fab")
		)
		(fp_line
			(start -0.2794 -0.1016)
			(end 0.2794 -0.1016)
			(stroke
				(width 0.1)
				(type default)
			)
			(layer "B.Fab")
		)
		(fp_line
			(start 0.2794 0.9906)
			(end -0.2794 0.9906)
			(stroke
				(width 0.1)
				(type default)
			)
			(layer "B.Fab")
		)
		(fp_line
			(start -0.2794 0.9906)
			(end -0.2794 -0.1016)
			(stroke
				(width 0.1)
				(type default)
			)
			(layer "B.Fab")
		)
		(pad "1" smd rect
			(at 0 0 270)
			(size 0.508 0.508)
			(layers "B.Cu" "B.Mask" "B.Paste")
			(net "P3V3_STBY")
		)
		(pad "2" smd rect
			(at 0 0.889 270)
			(size 0.508 0.508)
			(layers "B.Cu" "B.Mask" "B.Paste")
			(net "PU_JTAG_BMC_RTCK")
		)
		(zone
			(layer "B.Cu")
			(hatch none 0.5)
			(connect_pads
				(clearance 0)
			)
			(min_thickness 0.25)
			(keepout
				(tracks allowed)
				(vias not_allowed)
				(pads allowed)
				(copperpour not_allowed)
				(footprints allowed)
			)
			(placement
				(enabled no)
				(sheetname "")
			)
			(fill
				(thermal_gap 0.5)
				(thermal_bridge_width 0.5)
				(island_removal_mode 0)
			)
			(polygon
				(pts
					(xy 401.853146 -36.585652) (xy 401.853146 -36.077652) (xy 402.234146 -36.077652) (xy 402.234146 -36.585652)
				)
			)
		)
		(zone
			(layer "B.Cu")
			(hatch none 0.5)
			(connect_pads
				(clearance 0)
			)
			(min_thickness 0.25)
			(keepout
				(tracks not_allowed)
				(vias allowed)
				(pads allowed)
				(copperpour not_allowed)
				(footprints allowed)
			)
			(placement
				(enabled no)
				(sheetname "")
			)
			(fill
				(thermal_gap 0.5)
				(thermal_bridge_width 0.5)
				(island_removal_mode 0)
			)
			(polygon
				(pts
					(xy 402.234146 -36.585652) (xy 402.234146 -36.077652) (xy 401.853146 -36.077652) (xy 401.853146 -36.585652)
				)
			)
		)
	)
	(footprint ""
		(layer "B.Cu")
		(at 410.464 -152.273 90)
		(property "Reference" "C2L12"
			(at 0 0 90)
			(layer "B.SilkS")
			(hide yes)
			(effects
				(font
					(size 1.27 1.27)
				)
				(justify mirror)
			)
		)
		(property "Value" ""
			(at 0 0 90)
			(layer "B.Fab")
			(effects
				(font
					(size 1.27 1.27)
				)
				(justify mirror)
			)
		)
		(duplicate_pad_numbers_are_jumpers no)
		(fp_poly
			(pts
				(xy -0.3048 -0.1016) (xy -0.3048 0.9906) (xy 0.3048 0.9906) (xy 0.3048 -0.1016)
			)
			(stroke
				(width 0)
				(type default)
			)
			(fill no)
			(layer "B.CrtYd")
		)
		(fp_line
			(start 0.3048 -0.1016)
			(end 0.3048 0.9906)
			(stroke
				(width 0.1)
				(type default)
			)
			(layer "B.Fab")
		)
		(fp_line
			(start -0.3048 -0.1016)
			(end 0.3048 -0.1016)
			(stroke
				(width 0.1)
				(type default)
			)
			(layer "B.Fab")
		)
		(fp_line
			(start 0.3048 0.9906)
			(end -0.3048 0.9906)
			(stroke
				(width 0.1)
				(type default)
			)
			(layer "B.Fab")
		)
		(fp_line
			(start -0.3048 0.9906)
			(end -0.3048 -0.1016)
			(stroke
				(width 0.1)
				(type default)
			)
			(layer "B.Fab")
		)
		(pad "1" smd rect
			(at 0 0 270)
			(size 0.508 0.508)
			(layers "B.Cu" "B.Mask" "B.Paste")
			(net "SATA6G_PCH_PCIE_UP_SATA_RXP<5>")
		)
		(pad "2" smd rect
			(at 0 0.889 270)
			(size 0.508 0.508)
			(layers "B.Cu" "B.Mask" "B.Paste")
			(net "SATA6G_P5_RX_C_DP")
		)
		(zone
			(layer "B.Cu")
			(hatch none 0.5)
			(connect_pads
				(clearance 0)
			)
			(min_thickness 0.25)
			(keepout
				(tracks allowed)
				(vias not_allowed)
				(pads allowed)
				(copperpour not_allowed)
				(footprints allowed)
			)
			(placement
				(enabled no)
				(sheetname "")
			)
			(fill
				(thermal_gap 0.5)
				(thermal_bridge_width 0.5)
				(island_removal_mode 0)
			)
			(polygon
				(pts
					(xy 410.718 -152.527) (xy 410.718 -152.019) (xy 411.099 -152.019) (xy 411.099 -152.527)
				)
			)
		)
		(zone
			(layer "B.Cu")
			(hatch none 0.5)
			(connect_pads
				(clearance 0)
			)
			(min_thickness 0.25)
			(keepout
				(tracks not_allowed)
				(vias allowed)
				(pads allowed)
				(copperpour not_allowed)
				(footprints allowed)
			)
			(placement
				(enabled no)
				(sheetname "")
			)
			(fill
				(thermal_gap 0.5)
				(thermal_bridge_width 0.5)
				(island_removal_mode 0)
			)
			(polygon
				(pts
					(xy 411.099 -152.527) (xy 411.099 -152.019) (xy 410.718 -152.019) (xy 410.718 -152.527)
				)
			)
		)
	)
	(footprint ""
		(layer "B.Cu")
		(at 450.8627 -144.1831 -90)
		(property "Reference" "FB25W4"
			(at 0 0 90)
			(layer "B.SilkS")
			(hide yes)
			(effects
				(font
					(size 1.27 1.27)
				)
				(justify mirror)
			)
		)
		(property "Value" "*"
			(at 0.0127 -7.01675 270)
			(unlocked yes)
			(layer "B.Fab")
			(hide yes)
			(effects
				(font
					(size 0.889 0.889)
					(thickness 0.1524)
				)
				(justify mirror)
			)
		)
		(property "Device Type" "BLM15AG121SN-1GP_DISCRET-G-BLMA"
			(at 0.0127 -8.54075 270)
			(unlocked yes)
			(layer "B.Fab")
			(hide yes)
			(effects
				(font
					(size 0.889 0.889)
					(thickness 0.1524)
				)
				(justify mirror)
			)
		)
		(duplicate_pad_numbers_are_jumpers no)
		(fp_line
			(start 0.508 0.9398)
			(end 0.508 0.8636)
			(stroke
				(width 0.1524)
				(type default)
			)
			(layer "B.SilkS")
		)
		(fp_line
			(start -0.508 -0.9398)
			(end 0.508 -0.9398)
			(stroke
				(width 0.1524)
				(type default)
			)
			(layer "B.SilkS")
		)
		(fp_line
			(start 0.508 -0.9398)
			(end 0.508 0.9398)
			(stroke
				(width 0.1524)
				(type default)
			)
			(layer "B.SilkS")
		)
		(fp_rect
			(start 0.508 0.9398)
			(end -0.508 -0.9398)
			(stroke
				(width 0)
				(type default)
			)
			(fill no)
			(layer "B.CrtYd")
		)
		(fp_rect
			(start 0.508 0.9398)
			(end -0.508 -0.9398)
			(stroke
				(width 0)
				(type default)
			)
			(fill no)
			(layer "B.Fab")
		)
		(pad "1" smd custom
			(at 0 -0.4445 90)
			(size 0.1397 0.1397)
			(layers "B.Cu" "B.Mask" "B.Paste")
			(net "XDP_TDI_R")
			(options
				(clearance outline)
				(anchor circle)
			)
			(primitives
				(gr_poly
					(pts
						(arc
							(start -0.1778 0.2794)
							(mid -0.249642 0.249642)
							(end -0.2794 0.1778)
						)
						(arc
							(start -0.2794 -0.1778)
							(mid -0.249642 -0.249642)
							(end -0.1778 -0.2794)
						)
						(arc
							(start 0.1778 -0.2794)
							(mid 0.249642 -0.249642)
							(end 0.2794 -0.1778)
						)
						(arc
							(start 0.2794 0.1778)
							(mid 0.249642 0.249642)
							(end 0.1778 0.2794)
						)
					)
					(width 0)
					(fill yes)
				)
			)
		)
		(pad "2" smd custom
			(at 0 0.4445 90)
			(size 0.1397 0.1397)
			(layers "B.Cu" "B.Mask" "B.Paste")
			(net "XDP_TDI")
			(options
				(clearance outline)
				(anchor circle)
			)
			(primitives
				(gr_poly
					(pts
						(arc
							(start -0.1778 0.2794)
							(mid -0.249642 0.249642)
							(end -0.2794 0.1778)
						)
						(arc
							(start -0.2794 -0.1778)
							(mid -0.249642 -0.249642)
							(end -0.1778 -0.2794)
						)
						(arc
							(start 0.1778 -0.2794)
							(mid 0.249642 -0.249642)
							(end 0.2794 -0.1778)
						)
						(arc
							(start 0.2794 0.1778)
							(mid 0.249642 0.249642)
							(end 0.1778 0.2794)
						)
					)
					(width 0)
					(fill yes)
				)
			)
		)
	)
)
